#ISCELL
  mstr_misc dns *
  *
#ISCELL
  pure_quanta quanta_title_block_c *
  *
#ISCELL
  logical_power universal_gnd *
  page145_i10
#CELL
  pure_quanta mosfet_nch_dual *
  page145_i100
#CELL
  pure_quanta q_res *
  page145_i101
#ISCELL
  logical_power universal_power *
  page145_i102
#ISCELL
  logical_power universal_gnd *
  page145_i103
#ISCELL
  logical_power universal_gnd *
  page145_i104
#CELL
  pure_quanta q_cap *
  page145_i105
#ISCELL
  standard offpage *
  page145_i106
#ISCELL
  logical_power universal_gnd *
  page145_i108
#CELL
  pure_quanta q_res *
  page145_i109
#ISCELL
  logical_power universal_gnd *
  page145_i11
#ISCELL
  logical_power universal_power *
  page145_i110
#CELL
  pure_quanta q_cap *
  page145_i111
#ISCELL
  logical_power universal_gnd *
  page145_i112
#ISCELL
  logical_power universal_gnd *
  page145_i113
#CELL
  pure_quanta q_cap *
  page145_i114
#ISCELL
  logical_power universal_gnd *
  page145_i115
#CELL
  pure_quanta q_cap *
  page145_i116
#CELL
  pure_quanta mosfet_nch_dual *
  page145_i117
#CELL
  pure_quanta mosfet_nch_dual *
  page145_i118
#CELL
  pure_quanta mosfet_nch_dual *
  page145_i119
#ISCELL
  logical_power universal_gnd *
  page145_i12
#CELL
  pure_quanta mosfet_nch_dual *
  page145_i120
#CELL
  pure_quanta mosfet_nch_dual *
  page145_i121
#CELL
  pure_quanta mosfet_nch_dual *
  page145_i122
#ISCELL
  logical_power universal_power *
  page145_i123
#ISCELL
  standard offpage *
  page145_i124
#CELL
  pure_quanta q_cap *
  page145_i125
#ISCELL
  logical_power universal_gnd *
  page145_i126
#CELL
  pure_quanta q_res *
  page145_i127
#ISCELL
  logical_power universal_power *
  page145_i128
#CELL
  pure_quanta q_res *
  page145_i129
#ISCELL
  logical_power universal_power *
  page145_i13
#ISCELL
  logical_power universal_gnd *
  page145_i130
#ISCELL
  logical_power universal_gnd *
  page145_i131
#ISCELL
  logical_power universal_power *
  page145_i132
#CELL
  pure_quanta q_res *
  page145_i134
#ISCELL
  logical_power universal_gnd *
  page145_i135
#ISCELL
  standard offpage *
  page145_i136
#ISCELL
  standard offpage *
  page145_i137
#ISCELL
  logical_power universal_gnd *
  page145_i138
#CELL
  pure_quanta q_res *
  page145_i139
#CELL
  pure_quanta q_res *
  page145_i14
#ISCELL
  logical_power universal_power *
  page145_i141
#ISCELL
  logical_power universal_gnd *
  page145_i142
#ISCELL
  logical_power universal_gnd *
  page145_i143
#CELL
  pure_quanta q_res *
  page145_i144
#ISCELL
  logical_power universal_power *
  page145_i145
#CELL
  pure_quanta q_res *
  page145_i146
#ISCELL
  logical_power universal_gnd *
  page145_i147
#CELL
  pure_quanta q_cap *
  page145_i148
#ISCELL
  standard offpage *
  page145_i149
#ISCELL
  logical_power universal_power *
  page145_i150
#CELL
  pure_quanta mosfet_nch_dual *
  page145_i151
#CELL
  pure_quanta mosfet_nch_dual *
  page145_i152
#ISCELL
  logical_power universal_power *
  page145_i153
#CELL
  pure_quanta mosfet_nch_dual *
  page145_i154
#ISCELL
  standard offpage *
  page145_i155
#CELL
  pure_quanta q_cap *
  page145_i156
#ISCELL
  logical_power universal_gnd *
  page145_i157
#CELL
  pure_quanta q_res *
  page145_i158
#CELL
  pure_quanta mosfet_nch_dual *
  page145_i159
#ISCELL
  logical_power universal_power *
  page145_i16
#ISCELL
  logical_power universal_gnd *
  page145_i160
#ISCELL
  logical_power universal_power *
  page145_i161
#CELL
  pure_quanta q_res *
  page145_i162
#ISCELL
  logical_power universal_gnd *
  page145_i163
#ISCELL
  logical_power universal_power *
  page145_i164
#ISCELL
  logical_power universal_gnd *
  page145_i167
#ISCELL
  standard offpage *
  page145_i168
#ISCELL
  standard offpage *
  page145_i169
#CELL
  pure_quanta q_res *
  page145_i171
#CELL
  pure_quanta q_res *
  page145_i172
#CELL
  pure_quanta q_res *
  page145_i173
#CELL
  pure_quanta q_res *
  page145_i174
#CELL
  pure_quanta q_res *
  page145_i175
#CELL
  pure_quanta q_res *
  page145_i176
#CELL
  pure_quanta q_res *
  page145_i18
#CELL
  pure_quanta q_res *
  page145_i19
#ISCELL
  logical_power universal_power *
  page145_i21
#ISCELL
  standard offpage *
  page145_i22
#ISCELL
  logical_power universal_gnd *
  page145_i23
#CELL
  pure_quanta q_res *
  page145_i24
#ISCELL
  logical_power universal_power *
  page145_i25
#ISCELL
  standard offpage *
  page145_i28
#ISCELL
  logical_power universal_gnd *
  page145_i29
#CELL
  pure_quanta q_res *
  page145_i30
#ISCELL
  logical_power universal_power *
  page145_i31
#CELL
  pure_quanta mosfet_nch_dual *
  page145_i33
#CELL
  pure_quanta mosfet_nch_dual *
  page145_i35
#CELL
  pure_quanta mosfet_nch_dual *
  page145_i37
#ISCELL
  logical_power universal_power *
  page145_i46
#ISCELL
  logical_power universal_power *
  page145_i47
#ISCELL
  logical_power universal_power *
  page145_i49
#ISCELL
  logical_power universal_power *
  page145_i51
#ISCELL
  logical_power universal_power *
  page145_i53
#ISCELL
  logical_power universal_gnd *
  page145_i55
#CELL
  pure_quanta q_res *
  page145_i56
#ISCELL
  logical_power universal_gnd *
  page145_i57
#CELL
  pure_quanta q_res *
  page145_i58
#ISCELL
  logical_power universal_gnd *
  page145_i59
#ISCELL
  standard offpage *
  page145_i6
#CELL
  pure_quanta q_res *
  page145_i60
#ISCELL
  logical_power universal_gnd *
  page145_i61
#CELL
  pure_quanta q_res *
  page145_i62
#ISCELL
  logical_power universal_gnd *
  page145_i63
#CELL
  pure_quanta q_res *
  page145_i66
#CELL
  pure_quanta q_res *
  page145_i67
#CELL
  pure_quanta q_res *
  page145_i68
#ISCELL
  standard offpage *
  page145_i7
#ISCELL
  standard offpage *
  page145_i8
#CELL
  pure_quanta q_res *
  page145_i80
#CELL
  pure_quanta mosfet_nch_dual *
  page145_i82
#ISCELL
  logical_power universal_gnd *
  page145_i83
#CELL
  pure_quanta q_res *
  page145_i84
#ISCELL
  logical_power universal_power *
  page145_i85
#ISCELL
  standard offpage *
  page145_i86
#ISCELL
  standard offpage *
  page145_i87
#CELL
  pure_quanta mosfet_nch_dual *
  page145_i88
#ISCELL
  logical_power universal_gnd *
  page145_i89
#ISCELL
  logical_power universal_power *
  page145_i90
#CELL
  pure_quanta q_res *
  page145_i91
#CELL
  pure_quanta q_cap *
  page145_i92
#ISCELL
  logical_power universal_gnd *
  page145_i93
#ISCELL
  standard offpage *
  page145_i94
#ISCELL
  logical_power universal_gnd *
  page145_i96
#CELL
  pure_quanta q_res *
  page145_i97
#ISCELL
  logical_power universal_power *
  page145_i98
#ISCELL
  standard offpage *
  page145_i99
